# SCM (Grand Teton) — schematic netlist excerpt (pin names and nets, part order shuffled) for the footprints in the layout excerpt that follows; sources: Cadence DE-HDL packaged netlist, KiCad conversion of 12092022_DA0F0TMDCD0_F0T_Management_Board_D_brd_V3_OCP.brd

PR541  Q_RES  5.1 5% CHIP  pkg 0402LF  page 56 : A = PVCC2_AUX ; B = P1V0_AUX_VCC
R348  Q_RES  120 1% CHIP  pkg 0402LF  page 20 : A = GND ; B = M_BMC_DDR4_MODT

(kicad_pcb
	(version 20260206)
	(generator "pcbnew")
	(generator_version "10.0")
	(general
		(thickness 1.6)
		(legacy_teardrops no)
	)
	(paper "A4")
	(title_block
		(title "12092022_DA0F0TMDCD0_F0T_Management_Board_D_brd_V3_OCP.brd")
		(comment 1 "Grand Teton / footprints 374-375 of 1440")
	)
	(layers
		(0 "F.Cu" signal "TOP")
		(4 "In1.Cu" signal "GND")
		(6 "In2.Cu" signal "IN1")
		(8 "In3.Cu" signal "GND1")
		(10 "In4.Cu" signal "IN2")
		(12 "In5.Cu" signal "VCC")
		(14 "In6.Cu" signal "VCC1")
		(16 "In7.Cu" signal "IN3")
		(18 "In8.Cu" signal "GND2")
		(20 "In9.Cu" signal "IN4")
		(22 "In10.Cu" signal "GND3")
		(2 "B.Cu" signal "BOTTOM")
		(9 "F.Adhes" user "F.Adhesive")
		(11 "B.Adhes" user "B.Adhesive")
		(13 "F.Paste" user "Package Geometry/Pastemask Top")
		(15 "B.Paste" user "Package Geometry/Pastemask Bottom")
		(5 "F.SilkS" user "Ref Des/Silkscreen Top")
		(7 "B.SilkS" user "Ref Des/Silkscreen Bottom")
		(1 "F.Mask" user "Board Geometry/Soldermask Top")
		(3 "B.Mask" user "Board Geometry/Soldermask Bottom")
		(17 "Dwgs.User" user "User.Drawings")
		(19 "Cmts.User" user "User.Comments")
		(21 "Eco1.User" user "User.Eco1")
		(23 "Eco2.User" user "User.Eco2")
		(25 "Edge.Cuts" user "Board Geometry/Outline")
		(27 "Margin" user)
		(31 "F.CrtYd" user "Package Geometry/Place Bound Top")
		(29 "B.CrtYd" user "Package Geometry/Place Bound Bottom")
		(35 "F.Fab" user "Ref Des/Assembly Top")
		(33 "B.Fab" user "Ref Des/Assembly Bottom")
	)
	(footprint ""
		(layer "F.Cu")
		(at 23.34895 -30.631384 -90)
		(property "Reference" "PR541"
			(at 0 0 270)
			(layer "F.SilkS")
			(hide yes)
			(effects
				(font
					(size 1.27 1.27)
				)
			)
		)
		(property "Value" ""
			(at 0 0 270)
			(layer "F.Fab")
			(effects
				(font
					(size 1.27 1.27)
				)
			)
		)
		(duplicate_pad_numbers_are_jumpers no)
		(fp_line
			(start -0.7874 0.4064)
			(end -0.7874 -0.4064)
			(stroke
				(width 0.1524)
				(type default)
			)
			(layer "F.SilkS")
		)
		(fp_line
			(start 0.7874 0.4064)
			(end -0.7874 0.4064)
			(stroke
				(width 0.1524)
				(type default)
			)
			(layer "F.SilkS")
		)
		(fp_line
			(start -0.7874 -0.4064)
			(end 0.7874 -0.4064)
			(stroke
				(width 0.1524)
				(type default)
			)
			(layer "F.SilkS")
		)
		(fp_line
			(start 0.7874 -0.4064)
			(end 0.7874 0.4064)
			(stroke
				(width 0.1524)
				(type default)
			)
			(layer "F.SilkS")
		)
		(fp_line
			(start -0.67945 0.3048)
			(end -0.67945 -0.305054)
			(stroke
				(width 0.1)
				(type default)
			)
			(layer "F.Fab")
		)
		(fp_line
			(start -0.12065 0.3048)
			(end -0.67945 0.3048)
			(stroke
				(width 0.1)
				(type default)
			)
			(layer "F.Fab")
		)
		(fp_line
			(start 0.120396 0.3048)
			(end 0.120396 0.2794)
			(stroke
				(width 0.1)
				(type default)
			)
			(layer "F.Fab")
		)
		(fp_line
			(start 0.67945 0.3048)
			(end 0.120396 0.3048)
			(stroke
				(width 0.1)
				(type default)
			)
			(layer "F.Fab")
		)
		(fp_line
			(start -0.12065 0.2794)
			(end -0.12065 0.3048)
			(stroke
				(width 0.1)
				(type default)
			)
			(layer "F.Fab")
		)
		(fp_line
			(start 0.120396 0.2794)
			(end -0.12065 0.2794)
			(stroke
				(width 0.1)
				(type default)
			)
			(layer "F.Fab")
		)
		(fp_line
			(start -0.12065 -0.2794)
			(end 0.12065 -0.2794)
			(stroke
				(width 0.1)
				(type default)
			)
			(layer "F.Fab")
		)
		(fp_line
			(start 0.12065 -0.2794)
			(end 0.12065 -0.3048)
			(stroke
				(width 0.1)
				(type default)
			)
			(layer "F.Fab")
		)
		(fp_line
			(start 0.12065 -0.3048)
			(end 0.67945 -0.3048)
			(stroke
				(width 0.1)
				(type default)
			)
			(layer "F.Fab")
		)
		(fp_line
			(start 0.67945 -0.3048)
			(end 0.67945 0.3048)
			(stroke
				(width 0.1)
				(type default)
			)
			(layer "F.Fab")
		)
		(fp_line
			(start -0.67945 -0.305054)
			(end -0.12065 -0.305054)
			(stroke
				(width 0.1)
				(type default)
			)
			(layer "F.Fab")
		)
		(fp_line
			(start -0.12065 -0.305054)
			(end -0.12065 -0.2794)
			(stroke
				(width 0.1)
				(type default)
			)
			(layer "F.Fab")
		)
		(pad "1" smd circle
			(at -0.40005 0 270)
			(size 0 0)
			(layers "F.Cu" "F.Mask" "F.Paste")
			(net "PVCC2_AUX")
		)
		(pad "2" smd circle
			(at 0.40005 0 270)
			(size 0 0)
			(layers "F.Cu" "F.Mask" "F.Paste")
			(net "P1V0_AUX_VCC")
		)
	)
	(footprint ""
		(layer "F.Cu")
		(at 79.739744 -35.527488 90)
		(property "Reference" "R348"
			(at 0 0 90)
			(layer "F.SilkS")
			(hide yes)
			(effects
				(font
					(size 1.27 1.27)
				)
			)
		)
		(property "Value" ""
			(at 0 0 90)
			(layer "F.Fab")
			(effects
				(font
					(size 1.27 1.27)
				)
			)
		)
		(duplicate_pad_numbers_are_jumpers no)
		(fp_line
			(start 0.7874 -0.4064)
			(end 0.7874 0.4064)
			(stroke
				(width 0.1524)
				(type default)
			)
			(layer "F.SilkS")
		)
		(fp_line
			(start -0.7874 -0.4064)
			(end 0.7874 -0.4064)
			(stroke
				(width 0.1524)
				(type default)
			)
			(layer "F.SilkS")
		)
		(fp_line
			(start 0.7874 0.4064)
			(end -0.7874 0.4064)
			(stroke
				(width 0.1524)
				(type default)
			)
			(layer "F.SilkS")
		)
		(fp_line
			(start -0.7874 0.4064)
			(end -0.7874 -0.4064)
			(stroke
				(width 0.1524)
				(type default)
			)
			(layer "F.SilkS")
		)
		(fp_line
			(start -0.12065 -0.305054)
			(end -0.12065 -0.2794)
			(stroke
				(width 0.1)
				(type default)
			)
			(layer "F.Fab")
		)
		(fp_line
			(start -0.67945 -0.305054)
			(end -0.12065 -0.305054)
			(stroke
				(width 0.1)
				(type default)
			)
			(layer "F.Fab")
		)
		(fp_line
			(start 0.67945 -0.3048)
			(end 0.67945 0.3048)
			(stroke
				(width 0.1)
				(type default)
			)
			(layer "F.Fab")
		)
		(fp_line
			(start 0.12065 -0.3048)
			(end 0.67945 -0.3048)
			(stroke
				(width 0.1)
				(type default)
			)
			(layer "F.Fab")
		)
		(fp_line
			(start 0.12065 -0.2794)
			(end 0.12065 -0.3048)
			(stroke
				(width 0.1)
				(type default)
			)
			(layer "F.Fab")
		)
		(fp_line
			(start -0.12065 -0.2794)
			(end 0.12065 -0.2794)
			(stroke
				(width 0.1)
				(type default)
			)
			(layer "F.Fab")
		)
		(fp_line
			(start 0.120396 0.2794)
			(end -0.12065 0.2794)
			(stroke
				(width 0.1)
				(type default)
			)
			(layer "F.Fab")
		)
		(fp_line
			(start -0.12065 0.2794)
			(end -0.12065 0.3048)
			(stroke
				(width 0.1)
				(type default)
			)
			(layer "F.Fab")
		)
		(fp_line
			(start 0.67945 0.3048)
			(end 0.120396 0.3048)
			(stroke
				(width 0.1)
				(type default)
			)
			(layer "F.Fab")
		)
		(fp_line
			(start 0.120396 0.3048)
			(end 0.120396 0.2794)
			(stroke
				(width 0.1)
				(type default)
			)
			(layer "F.Fab")
		)
		(fp_line
			(start -0.12065 0.3048)
			(end -0.67945 0.3048)
			(stroke
				(width 0.1)
				(type default)
			)
			(layer "F.Fab")
		)
		(fp_line
			(start -0.67945 0.3048)
			(end -0.67945 -0.305054)
			(stroke
				(width 0.1)
				(type default)
			)
			(layer "F.Fab")
		)
		(pad "1" smd circle
			(at -0.40005 0 90)
			(size 0 0)
			(layers "F.Cu" "F.Mask" "F.Paste")
			(net "GND")
		)
		(pad "2" smd circle
			(at 0.40005 0 90)
			(size 0 0)
			(layers "F.Cu" "F.Mask" "F.Paste")
			(net "M_BMC_DDR4_MODT")
		)
	)
)
